# T6G (Grand Teton) — schematic netlist excerpt (pin names and nets, part order shuffled) for the footprints in the layout excerpt that follows; sources: Cadence DE-HDL packaged netlist, KiCad conversion of 04192023_DAF0TMB3IC0_F0TG_MB_C_brd_V02_OCP.brd

R3207  Q_RES  100K 1% CHIP  pkg 0402LF  page 138 : A = FB_BMC_ISOLATE1 ; B = GND
PC4  Q_CAP  0.1UF 25V 10% X7R  pkg 0402  page 207 : A = PVDD11_S3_P0_VCC ; B = GND

(kicad_pcb
	(version 20260206)
	(generator "pcbnew")
	(generator_version "10.0")
	(general
		(thickness 1.6)
		(legacy_teardrops no)
	)
	(paper "A4")
	(title_block
		(title "04192023_DAF0TMB3IC0_F0TG_MB_C_brd_V02_OCP.brd")
		(comment 1 "Grand Teton / footprints 4316-4317 of 8354")
	)
	(layers
		(0 "F.Cu" signal "TOP")
		(4 "In1.Cu" signal "GND")
		(6 "In2.Cu" signal "IN1")
		(8 "In3.Cu" signal "GND1")
		(10 "In4.Cu" signal "IN2")
		(12 "In5.Cu" signal "GND2")
		(14 "In6.Cu" signal "IN3")
		(16 "In7.Cu" signal "GND3")
		(18 "In8.Cu" signal "VCC")
		(20 "In9.Cu" signal "VCC1")
		(22 "In10.Cu" signal "GND4")
		(24 "In11.Cu" signal "IN4")
		(26 "In12.Cu" signal "GND5")
		(28 "In13.Cu" signal "IN5")
		(30 "In14.Cu" signal "GND6")
		(32 "In15.Cu" signal "IN6")
		(34 "In16.Cu" signal "GND7")
		(2 "B.Cu" signal "BOTTOM")
		(9 "F.Adhes" user "F.Adhesive")
		(11 "B.Adhes" user "B.Adhesive")
		(13 "F.Paste" user "Package Geometry/Pastemask Top")
		(15 "B.Paste" user "Package Geometry/Pastemask Bottom")
		(5 "F.SilkS" user "Ref Des/Silkscreen Top")
		(7 "B.SilkS" user "Ref Des/Silkscreen Bottom")
		(1 "F.Mask" user "Board Geometry/Soldermask Top")
		(3 "B.Mask" user "Board Geometry/Soldermask Bottom")
		(17 "Dwgs.User" user "User.Drawings")
		(19 "Cmts.User" user "User.Comments")
		(21 "Eco1.User" user "User.Eco1")
		(23 "Eco2.User" user "User.Eco2")
		(25 "Edge.Cuts" user "Board Geometry/Outline")
		(27 "Margin" user)
		(31 "F.CrtYd" user "Package Geometry/Place Bound Top")
		(29 "B.CrtYd" user "Package Geometry/Place Bound Bottom")
		(35 "F.Fab" user "Ref Des/Assembly Top")
		(33 "B.Fab" user "Ref Des/Assembly Bottom")
	)
	(footprint ""
		(layer "F.Cu")
		(at 49.38268 -36.820348)
		(property "Reference" "R3207"
			(at 0 0 0)
			(layer "F.SilkS")
			(hide yes)
			(effects
				(font
					(size 1.27 1.27)
				)
			)
		)
		(property "Value" ""
			(at 0 0 0)
			(layer "F.Fab")
			(effects
				(font
					(size 1.27 1.27)
				)
			)
		)
		(duplicate_pad_numbers_are_jumpers no)
		(fp_line
			(start -0.7874 -0.4064)
			(end 0.7874 -0.4064)
			(stroke
				(width 0.1524)
				(type default)
			)
			(layer "F.SilkS")
		)
		(fp_line
			(start -0.7874 0.4064)
			(end -0.7874 -0.4064)
			(stroke
				(width 0.1524)
				(type default)
			)
			(layer "F.SilkS")
		)
		(fp_line
			(start 0.7874 -0.4064)
			(end 0.7874 0.4064)
			(stroke
				(width 0.1524)
				(type default)
			)
			(layer "F.SilkS")
		)
		(fp_line
			(start 0.7874 0.4064)
			(end -0.7874 0.4064)
			(stroke
				(width 0.1524)
				(type default)
			)
			(layer "F.SilkS")
		)
		(fp_line
			(start -0.67945 -0.305054)
			(end -0.12065 -0.305054)
			(stroke
				(width 0.1)
				(type default)
			)
			(layer "F.Fab")
		)
		(fp_line
			(start -0.67945 0.3048)
			(end -0.67945 -0.305054)
			(stroke
				(width 0.1)
				(type default)
			)
			(layer "F.Fab")
		)
		(fp_line
			(start -0.12065 -0.305054)
			(end -0.12065 -0.2794)
			(stroke
				(width 0.1)
				(type default)
			)
			(layer "F.Fab")
		)
		(fp_line
			(start -0.12065 -0.2794)
			(end 0.12065 -0.2794)
			(stroke
				(width 0.1)
				(type default)
			)
			(layer "F.Fab")
		)
		(fp_line
			(start -0.12065 0.2794)
			(end -0.12065 0.3048)
			(stroke
				(width 0.1)
				(type default)
			)
			(layer "F.Fab")
		)
		(fp_line
			(start -0.12065 0.3048)
			(end -0.67945 0.3048)
			(stroke
				(width 0.1)
				(type default)
			)
			(layer "F.Fab")
		)
		(fp_line
			(start 0.120396 0.2794)
			(end -0.12065 0.2794)
			(stroke
				(width 0.1)
				(type default)
			)
			(layer "F.Fab")
		)
		(fp_line
			(start 0.120396 0.3048)
			(end 0.120396 0.2794)
			(stroke
				(width 0.1)
				(type default)
			)
			(layer "F.Fab")
		)
		(fp_line
			(start 0.12065 -0.3048)
			(end 0.67945 -0.3048)
			(stroke
				(width 0.1)
				(type default)
			)
			(layer "F.Fab")
		)
		(fp_line
			(start 0.12065 -0.2794)
			(end 0.12065 -0.3048)
			(stroke
				(width 0.1)
				(type default)
			)
			(layer "F.Fab")
		)
		(fp_line
			(start 0.67945 -0.3048)
			(end 0.67945 0.3048)
			(stroke
				(width 0.1)
				(type default)
			)
			(layer "F.Fab")
		)
		(fp_line
			(start 0.67945 0.3048)
			(end 0.120396 0.3048)
			(stroke
				(width 0.1)
				(type default)
			)
			(layer "F.Fab")
		)
		(pad "1" smd circle
			(at -0.40005 0)
			(size 0 0)
			(layers "F.Cu" "F.Mask" "F.Paste")
			(net "FB_BMC_ISOLATE1")
		)
		(pad "2" smd circle
			(at 0.40005 0)
			(size 0 0)
			(layers "F.Cu" "F.Mask" "F.Paste")
			(net "GND")
		)
	)
	(footprint ""
		(layer "F.Cu")
		(at 423.23766 -365.812578 90)
		(property "Reference" "PC4"
			(at 0 0 90)
			(layer "F.SilkS")
			(hide yes)
			(effects
				(font
					(size 1.27 1.27)
				)
			)
		)
		(property "Value" ""
			(at 0 0 90)
			(layer "F.Fab")
			(effects
				(font
					(size 1.27 1.27)
				)
			)
		)
		(duplicate_pad_numbers_are_jumpers no)
		(fp_line
			(start 0.7874 -0.4064)
			(end 0.7874 0.4064)
			(stroke
				(width 0.1524)
				(type default)
			)
			(layer "F.SilkS")
		)
		(fp_line
			(start -0.7874 -0.4064)
			(end 0.7874 -0.4064)
			(stroke
				(width 0.1524)
				(type default)
			)
			(layer "F.SilkS")
		)
		(fp_line
			(start 0.7874 0.4064)
			(end -0.7874 0.4064)
			(stroke
				(width 0.1524)
				(type default)
			)
			(layer "F.SilkS")
		)
		(fp_line
			(start -0.7874 0.4064)
			(end -0.7874 -0.4064)
			(stroke
				(width 0.1524)
				(type default)
			)
			(layer "F.SilkS")
		)
		(fp_line
			(start -0.12065 -0.305054)
			(end -0.12065 -0.2794)
			(stroke
				(width 0.1)
				(type default)
			)
			(layer "F.Fab")
		)
		(fp_line
			(start -0.67945 -0.305054)
			(end -0.12065 -0.305054)
			(stroke
				(width 0.1)
				(type default)
			)
			(layer "F.Fab")
		)
		(fp_line
			(start 0.67945 -0.3048)
			(end 0.67945 0.3048)
			(stroke
				(width 0.1)
				(type default)
			)
			(layer "F.Fab")
		)
		(fp_line
			(start 0.12065 -0.3048)
			(end 0.67945 -0.3048)
			(stroke
				(width 0.1)
				(type default)
			)
			(layer "F.Fab")
		)
		(fp_line
			(start 0.12065 -0.2794)
			(end 0.12065 -0.3048)
			(stroke
				(width 0.1)
				(type default)
			)
			(layer "F.Fab")
		)
		(fp_line
			(start -0.12065 -0.2794)
			(end 0.12065 -0.2794)
			(stroke
				(width 0.1)
				(type default)
			)
			(layer "F.Fab")
		)
		(fp_line
			(start 0.120396 0.2794)
			(end -0.12065 0.2794)
			(stroke
				(width 0.1)
				(type default)
			)
			(layer "F.Fab")
		)
		(fp_line
			(start -0.12065 0.2794)
			(end -0.12065 0.3048)
			(stroke
				(width 0.1)
				(type default)
			)
			(layer "F.Fab")
		)
		(fp_line
			(start 0.67945 0.3048)
			(end 0.120396 0.3048)
			(stroke
				(width 0.1)
				(type default)
			)
			(layer "F.Fab")
		)
		(fp_line
			(start 0.120396 0.3048)
			(end 0.120396 0.2794)
			(stroke
				(width 0.1)
				(type default)
			)
			(layer "F.Fab")
		)
		(fp_line
			(start -0.12065 0.3048)
			(end -0.67945 0.3048)
			(stroke
				(width 0.1)
				(type default)
			)
			(layer "F.Fab")
		)
		(fp_line
			(start -0.67945 0.3048)
			(end -0.67945 -0.305054)
			(stroke
				(width 0.1)
				(type default)
			)
			(layer "F.Fab")
		)
		(pad "1" smd circle
			(at -0.40005 0 90)
			(size 0 0)
			(layers "F.Cu" "F.Mask" "F.Paste")
			(net "PVDD11_S3_P0_VCC")
		)
		(pad "2" smd circle
			(at 0.40005 0 90)
			(size 0 0)
			(layers "F.Cu" "F.Mask" "F.Paste")
			(net "GND")
		)
	)
)
